FILE_TYPE = MACRO_DRAWING;
SET COLOR_WIRE YELLOW;
SET COLOR_PROP ORANGE;
SET COLOR_DOT WHITE;
SET COLOR_ARC YELLOW;
SET COLOR_BODY GREEN;
SET COLOR_NOTE PURPLE;
SET PROP_DISPLAY VALUE;
SET PAGE_NUMBER P142;
FORCEADD Q_LED..1
(-4650 1575);
FORCEPROP 1 LAST LOCATION D9
J 0
(-4750 1760);
DISPLAY 0.489362 (-4750 1760);
PAINT SKYBLUE (-4750 1760);
FORCEPROP 0 LAST $SEC 1
J 0
(-4750 1800);
DISPLAY 0.680851 (-4750 1800);
PAINT MONO (-4750 1800);
DISPLAY INVISIBLE (-4750 1800);
FORCEPROP 0 LAST CDS_SEC 1
J 0
(-4750 1800);
DISPLAY 0.680851 (-4750 1800);
DISPLAY INVISIBLE (-4750 1800);
FORCEPROP 0 LASTPIN (-4800 1575) $PN A
J 2
(-4810 1585);
DISPLAY 0.489362 (-4810 1585);
PAINT MONO (-4810 1585);
FORCEPROP 0 LASTPIN (-4500 1575) $PN C
J 0
(-4490 1585);
DISPLAY 0.489362 (-4490 1585);
PAINT MONO (-4490 1585);
FORCEPROP 2 LAST MANUF_PN LTST-C281TBKT-5A
J 0
(-4825 1425);
DISPLAY 0.680851 (-4825 1425);
FORCEPROP 2 LAST COLOR LED_BLUE
J 0
(-4825 1375);
DISPLAY 0.489362 (-4825 1375);
FORCEPROP 1 LAST MATERIAL IC
J 0
(-4750 1655);
DISPLAY 0.489362 (-4750 1655);
PAINT SKYBLUE (-4750 1655);
FORCEPROP 2 LAST PACK_TYPE SMLF
J 0
(-4825 1475);
DISPLAY 0.489362 (-4825 1475);
PAINT SKYBLUE (-4825 1475);
FORCEPROP 2 LAST CDS_LIB pure_quanta
J 2
(-4650 1575);
DISPLAY INVISIBLE (-4650 1575);
FORCEPROP 1 LAST NEEDS_NO_SIZE TRUE
J 0
(-4650 1575);
DISPLAY 0.468085 (-4650 1575);
PAINT GREEN (-4650 1575);
DISPLAY INVISIBLE (-4650 1575);
FORCEPROP 1 LAST PATH I79
J 0
(-4525 1655);
DISPLAY 0.723404 (-4525 1655);
PAINT GREEN (-4525 1655);
DISPLAY INVISIBLE (-4525 1655);
FORCEPROP 1 LAST PART_NUMBER BEBL0172Z00
J 0
(-4750 1710);
DISPLAY 0.489362 (-4750 1710);
PAINT SKYBLUE (-4750 1710);
DISPLAY INVISIBLE (-4750 1710);
FORCEADD MOSFET_N_GSD..1
R 2
(-3550 1300);
FORCEPROP 1 LAST LOCATION Q29
J 2
(-3651 1345);
DISPLAY 0.489362 (-3651 1345);
PAINT SKYBLUE (-3651 1345);
FORCEPROP 0 LAST $SEC 1
J 0
(-3650 1525);
DISPLAY 0.680851 (-3650 1525);
PAINT MONO (-3650 1525);
DISPLAY INVISIBLE (-3650 1525);
FORCEPROP 0 LAST CDS_SEC 1
J 0
(-3650 1525);
DISPLAY 0.680851 (-3650 1525);
DISPLAY INVISIBLE (-3650 1525);
FORCEPROP 0 LASTPIN (-3575 1450) $PN D
R 1
J 0
(-3585 1460);
DISPLAY 0.489362 (-3585 1460);
PAINT MONO (-3585 1460);
FORCEPROP 0 LASTPIN (-3375 1250) $PN G
J 0
(-3365 1260);
DISPLAY 0.489362 (-3365 1260);
PAINT MONO (-3365 1260);
FORCEPROP 0 LASTPIN (-3575 1150) $PN S
R 1
J 2
(-3585 1140);
DISPLAY 0.489362 (-3585 1140);
PAINT MONO (-3585 1140);
FORCEPROP 2 LAST VALUE NX138BK
J 2
(-3650 1425);
DISPLAY 0.489362 (-3650 1425);
PAINT SKYBLUE (-3650 1425);
FORCEPROP 1 LAST MATERIAL IC
J 2
(-3651 1200);
DISPLAY 0.489362 (-3651 1200);
PAINT SKYBLUE (-3651 1200);
FORCEPROP 2 LAST PART_TYPE SMLF
J 2
(-3650 1475);
DISPLAY 1.021277 (-3650 1475);
FORCEPROP 2 LAST CDS_LIB pure_quanta
J 2
(-3550 1300);
DISPLAY INVISIBLE (-3550 1300);
FORCEPROP 1 LAST CDS_LMAN_SYM_OUTLINE -100,100,100,-100
J 2
(-3550 1300);
DISPLAY 0.468085 (-3550 1300);
PAINT GREEN (-3550 1300);
DISPLAY INVISIBLE (-3550 1300);
FORCEPROP 1 LAST NEEDS_NO_SIZE TRUE
J 2
(-3550 1300);
DISPLAY 0.468085 (-3550 1300);
PAINT GREEN (-3550 1300);
DISPLAY INVISIBLE (-3550 1300);
FORCEPROP 1 LAST PATH I80
J 2
(-3550 1300);
DISPLAY 0.723404 (-3550 1300);
PAINT GREEN (-3550 1300);
DISPLAY INVISIBLE (-3550 1300);
FORCEPROP 1 LAST PART_NUMBER BAM01380023
J 2
(-3651 1280);
DISPLAY 0.489362 (-3651 1280);
PAINT SKYBLUE (-3651 1280);
DISPLAY INVISIBLE (-3651 1280);
FORCEADD MOSFET_N_GSD..1
R 2
(-2525 925);
FORCEPROP 1 LAST LOCATION Q30
J 2
(-2626 970);
DISPLAY 0.489362 (-2626 970);
PAINT SKYBLUE (-2626 970);
FORCEPROP 0 LAST $SEC 1
J 0
(-2625 1150);
DISPLAY 0.680851 (-2625 1150);
PAINT MONO (-2625 1150);
DISPLAY INVISIBLE (-2625 1150);
FORCEPROP 0 LAST CDS_SEC 1
J 0
(-2625 1150);
DISPLAY 0.680851 (-2625 1150);
DISPLAY INVISIBLE (-2625 1150);
FORCEPROP 0 LASTPIN (-2550 1075) $PN D
R 1
J 0
(-2560 1085);
DISPLAY 0.489362 (-2560 1085);
PAINT MONO (-2560 1085);
FORCEPROP 0 LASTPIN (-2350 875) $PN G
J 0
(-2340 885);
DISPLAY 0.489362 (-2340 885);
PAINT MONO (-2340 885);
FORCEPROP 0 LASTPIN (-2550 775) $PN S
R 1
J 2
(-2560 765);
DISPLAY 0.489362 (-2560 765);
PAINT MONO (-2560 765);
FORCEPROP 2 LAST VALUE NX138BK
J 2
(-2625 1050);
DISPLAY 0.489362 (-2625 1050);
PAINT SKYBLUE (-2625 1050);
FORCEPROP 1 LAST MATERIAL IC
J 2
(-2626 825);
DISPLAY 0.489362 (-2626 825);
PAINT SKYBLUE (-2626 825);
FORCEPROP 2 LAST PART_TYPE SMLF
J 2
(-2625 1100);
DISPLAY 1.021277 (-2625 1100);
FORCEPROP 1 LAST NEEDS_NO_SIZE TRUE
J 2
(-2525 925);
DISPLAY 0.468085 (-2525 925);
PAINT GREEN (-2525 925);
DISPLAY INVISIBLE (-2525 925);
FORCEPROP 1 LAST CDS_LMAN_SYM_OUTLINE -100,100,100,-100
J 2
(-2525 925);
DISPLAY 0.468085 (-2525 925);
PAINT GREEN (-2525 925);
DISPLAY INVISIBLE (-2525 925);
FORCEPROP 2 LAST CDS_LIB pure_quanta
J 0
(-2525 925);
DISPLAY INVISIBLE (-2525 925);
FORCEPROP 1 LAST PATH I81
J 2
(-2525 925);
DISPLAY 0.723404 (-2525 925);
PAINT GREEN (-2525 925);
DISPLAY INVISIBLE (-2525 925);
FORCEPROP 1 LAST PART_NUMBER BAM01380023
J 2
(-2626 905);
DISPLAY 0.489362 (-2626 905);
PAINT SKYBLUE (-2626 905);
DISPLAY INVISIBLE (-2626 905);
FORCEADD Q_RES..1
(-5550 1575);
FORCEPROP 1 LAST LOCATION R1444
J 0
(-5850 1575);
DISPLAY 0.489362 (-5850 1575);
PAINT SKYBLUE (-5850 1575);
FORCEPROP 0 LAST $SEC 1
J 0
(-5700 1625);
DISPLAY 0.680851 (-5700 1625);
PAINT MONO (-5700 1625);
DISPLAY INVISIBLE (-5700 1625);
FORCEPROP 0 LAST CDS_SEC 1
J 0
(-5700 1625);
DISPLAY 0.680851 (-5700 1625);
DISPLAY INVISIBLE (-5700 1625);
FORCEPROP 1 LASTPIN (-5650 1575) $PN 1
J 0
(-5638 1587);
DISPLAY 0.489362 (-5638 1587);
PAINT MONO (-5638 1587);
FORCEPROP 1 LASTPIN (-5450 1575) $PN 2
J 0
(-5488 1587);
DISPLAY 0.489362 (-5488 1587);
PAINT MONO (-5488 1587);
FORCEPROP 1 LAST PACK_TYPE 0402LF
J 0
(-5325 1500);
DISPLAY 0.489362 (-5325 1500);
PAINT SKYBLUE (-5325 1500);
FORCEPROP 1 LAST VALUE 130
J 2
(-5700 1500);
DISPLAY 0.489362 (-5700 1500);
PAINT SKYBLUE (-5700 1500);
FORCEPROP 1 LAST WATTAGE 1/16W
J 2
(-5475 1500);
DISPLAY 0.489362 (-5475 1500);
PAINT SKYBLUE (-5475 1500);
FORCEPROP 1 LAST TOLERANCE 1%
J 0
(-5675 1500);
DISPLAY 0.489362 (-5675 1500);
PAINT SKYBLUE (-5675 1500);
FORCEPROP 1 LAST MATERIAL CHIP
J 0
(-5450 1500);
DISPLAY 0.489362 (-5450 1500);
PAINT SKYBLUE (-5450 1500);
FORCEPROP 2 LAST CDS_LIB pure_quanta
J 0
(-5550 1575);
DISPLAY INVISIBLE (-5550 1575);
FORCEPROP 1 LAST PATH I82
J 0
(-5600 1725);
DISPLAY 0.978723 (-5600 1725);
PAINT WHITE (-5600 1725);
DISPLAY INVISIBLE (-5600 1725);
FORCEPROP 1 LAST PART_NUMBER CS11302FB03
J 0
(-5650 1650);
DISPLAY 0.489362 (-5650 1650);
PAINT SKYBLUE (-5650 1650);
DISPLAY INVISIBLE (-5650 1650);
FORCEADD UNIVERSAL_POWER..1
(-5925 1825);
FORCEPROP 3 LASTPIN (-5925 1775) SIG_NAME P3V3_AUX\g
J 0
(-5915 1785);
DISPLAY 0.659574 (-5915 1785);
PAINT MONO (-5915 1785);
DISPLAY INVISIBLE (-5915 1785);
FORCEPROP 1 LAST HDL_POWER P3V3_AUX
J 1
(-5925 1875);
DISPLAY 0.489362 (-5925 1875);
PAINT GREEN (-5925 1875);
FORCEPROP 2 LAST CDS_LIB pure_quanta_power
J 0
(-5925 1825);
DISPLAY INVISIBLE (-5925 1825);
FORCEPROP 2 LAST BOM_COST OCP3.0 
J 0
(-5925 1925);
DISPLAY 0.680851 (-5925 1925);
DISPLAY INVISIBLE (-5925 1925);
FORCEPROP 1 LAST PATH I83
J 0
(-5875 1850);
DISPLAY 0.872340 (-5875 1850);
PAINT AQUA (-5875 1850);
DISPLAY INVISIBLE (-5875 1850);
FORCEADD UNIVERSAL_GND..1
(-2550 625);
FORCEPROP 3 LASTPIN (-2550 675) SIG_NAME GND\g
J 0
(-2540 685);
DISPLAY 0.659574 (-2540 685);
PAINT MONO (-2540 685);
DISPLAY INVISIBLE (-2540 685);
FORCEPROP 1 LAST HDL_POWER GND
J 1
(-2525 550);
DISPLAY 0.489362 (-2525 550);
PAINT GREEN (-2525 550);
FORCEPROP 2 LAST CDS_LIB pure_quanta_power
J 0
(-2550 625);
DISPLAY INVISIBLE (-2550 625);
FORCEPROP 2 LAST BOM_COST MISC.
J 0
(-2525 600);
DISPLAY 0.680851 (-2525 600);
DISPLAY INVISIBLE (-2525 600);
FORCEPROP 1 LAST PATH I85
J 0
(-2475 625);
DISPLAY 0.872340 (-2475 625);
PAINT AQUA (-2475 625);
DISPLAY INVISIBLE (-2475 625);
FORCEADD UNIVERSAL_POWER..1
(-2550 1725);
FORCEPROP 3 LASTPIN (-2550 1675) SIG_NAME P3V3_AUX\g
J 0
(-2540 1685);
DISPLAY 0.659574 (-2540 1685);
PAINT MONO (-2540 1685);
DISPLAY INVISIBLE (-2540 1685);
FORCEPROP 1 LAST HDL_POWER P3V3_AUX
J 1
(-2550 1775);
DISPLAY 0.489362 (-2550 1775);
PAINT GREEN (-2550 1775);
FORCEPROP 2 LAST CDS_LIB pure_quanta_power
J 0
(-2550 1725);
DISPLAY INVISIBLE (-2550 1725);
FORCEPROP 1 LAST PATH I86
J 0
(-2500 1750);
DISPLAY 0.872340 (-2500 1750);
PAINT AQUA (-2500 1750);
DISPLAY INVISIBLE (-2500 1750);
FORCEADD Q_RES..2
(-2550 1500);
FORCEPROP 1 LAST LOCATION R1507
J 0
(-2505 1625);
DISPLAY 0.489362 (-2505 1625);
PAINT SKYBLUE (-2505 1625);
FORCEPROP 0 LAST $SEC 1
J 0
(-2500 1650);
DISPLAY 0.680851 (-2500 1650);
PAINT MONO (-2500 1650);
DISPLAY INVISIBLE (-2500 1650);
FORCEPROP 0 LAST CDS_SEC 1
J 0
(-2500 1650);
DISPLAY 0.680851 (-2500 1650);
DISPLAY INVISIBLE (-2500 1650);
FORCEPROP 1 LASTPIN (-2550 1600) $PN 1
J 0
(-2545 1562);
DISPLAY 0.489362 (-2545 1562);
PAINT MONO (-2545 1562);
FORCEPROP 1 LASTPIN (-2550 1400) $PN 2
J 0
(-2545 1410);
DISPLAY 0.489362 (-2545 1410);
PAINT MONO (-2545 1410);
FORCEPROP 1 LAST PACK_TYPE 0402LF
J 0
(-2510 1375);
DISPLAY 0.489362 (-2510 1375);
PAINT SKYBLUE (-2510 1375);
FORCEPROP 1 LAST TOLERANCE 1%
J 0
(-2505 1525);
DISPLAY 0.489362 (-2505 1525);
PAINT SKYBLUE (-2505 1525);
FORCEPROP 1 LAST WATTAGE 1/16W
J 0
(-2510 1475);
DISPLAY 0.489362 (-2510 1475);
PAINT SKYBLUE (-2510 1475);
FORCEPROP 1 LAST MATERIAL CHIP
J 0
(-2510 1425);
DISPLAY 0.489362 (-2510 1425);
PAINT SKYBLUE (-2510 1425);
FORCEPROP 1 LAST VALUE 1K
J 0
(-2505 1575);
DISPLAY 0.489362 (-2505 1575);
PAINT SKYBLUE (-2505 1575);
FORCEPROP 2 LAST CDS_LIB pure_quanta
J 0
(-2550 1500);
DISPLAY INVISIBLE (-2550 1500);
FORCEPROP 1 LAST PATH I87
J 0
(-2500 1675);
DISPLAY 0.978723 (-2500 1675);
PAINT WHITE (-2500 1675);
DISPLAY INVISIBLE (-2500 1675);
FORCEPROP 1 LAST PART_NUMBER CS21002FB06
J 0
(-2510 1325);
DISPLAY 0.638298 (-2510 1325);
PAINT SKYBLUE (-2510 1325);
DISPLAY INVISIBLE (-2510 1325);
FORCEADD OFFPAGE..4
(-1600 875);
FORCEPROP 2 LAST $XR0 81 
J 0
(-1414 875);
DISPLAY 0.638298 (-1414 875);
PAINT MONO (-1414 875);
FORCEPROP 2 LAST $XR1 167 
J 0
(-1324 875);
DISPLAY 0.638298 (-1324 875);
PAINT MONO (-1324 875);
FORCEPROP 2 LAST $XR2 28 
J 0
(-1204 875);
DISPLAY 0.638298 (-1204 875);
PAINT MONO (-1204 875);
FORCEPROP 2 LAST CDS_LIB standard
J 0
(-1600 875);
DISPLAY INVISIBLE (-1600 875);
FORCEPROP 1 LAST OFFPAGE TRUE
J 0
(-1275 750);
DISPLAY 0.872340 (-1275 750);
PAINT GREEN (-1275 750);
DISPLAY INVISIBLE (-1275 750);
FORCEPROP 1 LAST COMMENT_BODY TRUE
J 0
(-1625 775);
DISPLAY 0.872340 (-1625 775);
PAINT GREEN (-1625 775);
DISPLAY INVISIBLE (-1625 775);
FORCEPROP 2 LAST PATH I88
J 0
(-1425 950);
DISPLAY 0.680851 (-1425 950);
DISPLAY INVISIBLE (-1425 950);
FORCEADD QUANTA_TITLE_BLOCK_C..1
(0 0);
FORCEPROP 0 LAST CDS_CON_LAST_MODIFIED Thu Sep 14 16:12:16 2023
J 0
(-1885 15);
DISPLAY INVISIBLE (-1885 15);
FORCEPROP 1 LAST CUSTOM_TXT_CDS <CON_LAST_MODIFIED>
J 0
(-1885 15);
DISPLAY 0.978723 (-1885 15);
FORCEPROP 2 LAST CUSTOM_TXT_CDS <XR_PAGE_TITLE>
J 0
(-7890 5250);
DISPLAY 0.638298 (-7890 5250);
PAINT PINK (-7890 5250);
DISPLAY INVISIBLE (-7890 5250);
FORCEPROP 1 LAST CUSTOM_TXT_CDS <NAME_2>
J 0
(-3175 50);
FORCEPROP 1 LAST CUSTOM_TXT_CDS <NAME_1>
J 0
(-3175 175);
FORCEPROP 1 LAST CUSTOM_TXT_CDS <Q_NUMBER>
J 0
(-1403 103);
DISPLAY 1.212766 (-1403 103);
FORCEPROP 1 LAST CUSTOM_TXT_CDS <Q_PROJ>
J 0
(-2382 102);
DISPLAY 1.212766 (-2382 102);
FORCEPROP 1 LAST CUSTOM_TXT_CDS <Q_REV>
J 0
(-184 103);
DISPLAY 1.212766 (-184 103);
FORCEPROP 1 LAST CUSTOM_TXT_CDS <CON_PAGE_NUM> OF <CON_TOTAL_PAGES>
J 0
(-446 18);
DISPLAY 0.978723 (-446 18);
FORCEPROP 1 LAST Q_TITLE LED (1/2)
J 0
(-9250 50);
DISPLAY 2.446809 (-9250 50);
PAINT GREEN (-9250 50);
FORCEPROP 2 LAST CDS_XR_PAGE_TITLE CR-165 : @T6G_MB_LIB.T6G(SCH_1):PAGE165
J 0
(-7890 5250);
DISPLAY 0.638298 (-7890 5250);
PAINT PINK (-7890 5250);
DISPLAY INVISIBLE (-7890 5250);
FORCEPROP 2 LAST PAGE_BORDER TRUE
J 0
(-7890 5250);
DISPLAY 0.638298 (-7890 5250);
PAINT PINK (-7890 5250);
DISPLAY INVISIBLE (-7890 5250);
FORCEPROP 1 LAST CDS_LMAN_SYM_OUTLINE -9475,6775,100,-125
J 0
(0 0);
DISPLAY 0.468085 (0 0);
PAINT GREEN (0 0);
DISPLAY INVISIBLE (0 0);
FORCEPROP 2 LAST CDS_LIB pure_quanta
J 0
(0 0);
DISPLAY INVISIBLE (0 0);
FORCEPROP 1 LAST Q_DEPT BU9
J 1
(-3763 49);
DISPLAY 1.957447 (-3763 49);
PAINT GREEN (-3763 49);
DISPLAY INVISIBLE (-3763 49);
FORCEPROP 1 LAST COMMENT_BODY TRUE
J 0
(12 -13);
DISPLAY 0.978723 (12 -13);
PAINT GREEN (12 -13);
DISPLAY INVISIBLE (12 -13);
WIRE 16 -1 (-2550 1600)(-2550 1675);
WIRE 16 -1 (-2550 1400)(-2550 1250);
WIRE 16 -1 (-2550 1075)(-2550 1250);
WIRE 16 -1 (-2550 1250)(-3375 1250);
FORCEPROP 2 LAST SIG_NAME LED_BIOS_DBG_MODE_N
J 0
(-3285 1260);
DISPLAY 0.489362 (-3285 1260);
FORCEPROP 2 LASTPROP $XRERR UNIQUE?
J 0
(-3525 1260);
DISPLAY 0.638298 (-3525 1260);
PAINT MONO (-3525 1260);
DISPLAY INVISIBLE (-3525 1260);
WIRE 16 -1 (-2350 875)(-1650 875);
FORCEPROP 2 LAST SIG_NAME BIOS_DEBUG_MODE
J 0
(-2285 885);
DISPLAY 0.489362 (-2285 885);
WIRE 16 -1 (-2550 725)(-3575 725);
WIRE 16 -1 (-2550 775)(-2550 725);
WIRE 16 -1 (-2550 725)(-2550 675);
WIRE 16 -1 (-3575 725)(-3575 1150);
WIRE 16 -1 (-3575 1450)(-3575 1575);
WIRE 16 -1 (-3575 1575)(-4500 1575);
FORCEPROP 2 LAST SIG_NAME LED_BIOS_DBG_MODE
J 0
(-4210 1585);
DISPLAY 0.489362 (-4210 1585);
FORCEPROP 2 LASTPROP $XRERR UNIQUE?
J 0
(-4450 1585);
DISPLAY 0.638298 (-4450 1585);
PAINT MONO (-4450 1585);
DISPLAY INVISIBLE (-4450 1585);
WIRE 16 -1 (-4800 1575)(-5450 1575);
FORCEPROP 2 LAST SIG_NAME LED_BIOS_DBG_MODE_R
J 0
(-5385 1585);
DISPLAY 0.489362 (-5385 1585);
FORCEPROP 2 LASTPROP $XRERR UNIQUE?
J 0
(-5625 1585);
DISPLAY 0.638298 (-5625 1585);
PAINT MONO (-5625 1585);
DISPLAY INVISIBLE (-5625 1585);
WIRE 16 -1 (-5650 1575)(-5925 1575);
WIRE 16 -1 (-5925 1775)(-5925 1575);
DOT 1 (-2550 1250);
DOT 1 (-2550 725);
FORCENOTE
BIOS DBG MODE LED
(-2375 2000) 0;
DISPLAY LEFT (-2375 2000);
DISPLAY 2.000000 (-2375 2000);
QUIT
